# Lightning  PEB_Stackup.xlsx — 工作表2 (pcb-stackup)
|  |  |  |  |  |  | Version |  |  |  |  |  |  |  |  |  |  |  |  |  |  |  |  |  |  |  |  |
| Board Number: |  | 15105-1 |  |  |  | 02 |  |  |  |  |  |  |  |  |  |  |  |  |  |  |  |  |  |  |  |  |
| Project name: |  | Lightning_PMC |  |  |  |  |  |  |  |  |  |  |  |  |  |  |  |  |  |  |  |  |  |  |  |  |
| Model Name: |  | PEB |  |  |  |  |  |  |  |  |  |  |  |  |  |  |  |  |  |  |  |  |  |  |  |  |
| Layer Count: |  | 8 Layer |  |  |  |  |  |  |  |  |  |  |  |  |  |  |  |  |  |  |  |  |  |  |  |  |
| Date: |  | 42662 |  |  |  |  |  |  |  |  |  |  |  |  |  |  |  |  |  |  |  |  |  |  |  |  |
| Material: |  | TU863+VLP / NPG171+VLP |  |  |  |  |  |  |  | Single Ended Type(mil) |  |  |  |  | Differential Type(mil) |  |  |  |  |  |  |  |  |  |  |  |
| Gold Finger(Y/N) |  | Y |  |  |  |  |  |  | Imp | 50 |  |  |  | Imp | 85 |  |  |  |  |  | 100 |  |  |  |  |  |
| Customer: |  | XXXXX |  |  |  |  |  |  | Variation | Inner/Outer+/-5ohm |  |  |  | Variation | Inner/Outer+/-10% |  |  |  |  |  | Inner/Outer+/-10% |  |  |  |  |  |
| EE engineer |  | <name> |  |  |  |  |  |  | Bus | MISC./I2C |  |  |  | Bus | PCIe/Clock/USB |  |  |  |  |  | Clock/BMC DDR3 |  |  |  |  |  |
| SI Engineer |  | <name> |  |  |  |  |  |  |  |  |  |  |  |  |  |  |  |  |  |  |  |  |  |  |  |  |
|  |  |  |  |  |  |  |  |  | Type | SE |  |  |  | Type | DP |  |  |  |  |  | DP |  |  |  |  |  |
| Layer |  |  | Thickness |  | Glass/Copper Style | Er |  | Df(1G) | Layers | 1,3,6,8 |  |  |  | Layers | 1,3,6,8 |  |  |  |  |  | 1,3,6,8 |  |  |  |  |  |
|  |  | Cu oz | Wiwynn |  |  | Wiwynn |  |  |  | Wiwynn |  |  |  |  | Wiwynn |  |  |  |  |  | Wiwynn |  |  |  |  |  |
|  | Mask |  | 0.5 |  |  | 3.4 |  | 2.5000000000000001E-2 |  | Width | Imp | Width | Imp |  | Width | Space | Imp | Width | Space | Imp | Width | Space | Imp | Width | Space | Imp |
| Top | Signal | 0.5 oz+plating | 2.1 |  |  |  |  |  | S1 | 4.75(L2) | 50.46 |  |  | S1 | 5.38(L2) | 6.62 | 85.36 |  |  |  | 4.13(L2) | 9.3699999999999992 | 101.06 |  |  |  |
|  | Prepreg |  | 3 |  |  | 3.9 |  | 8.9999999999999993E-3 |  |  |  |  |  |  |  |  |  |  |  |  |  |  |  |  |  |  |
| L2 | GND | 1 oz | 1.3 |  |  |  |  |  | P2 | reference layer |  |  |  | P2 | reference layer |  |  |  |  |  | reference layer |  |  |  |  |  |
|  | Core |  | 4 |  |  | 3.9 |  | 8.9999999999999993E-3 |  |  |  |  |  |  |  |  |  |  |  |  |  |  |  |  |  |  |
| L3 | Signal | 1 oz | 1.3 |  |  |  |  |  | S3 | 5(L2/L4) | 49.19 |  |  | S3 | 5.5(L2/L4) | 7.5 | 84.85 |  |  |  | 4(L2/L4) | 8 | 97.55 |  |  |  |
|  | Prepreg |  | 16 |  |  | 4.2 |  | 8.9999999999999993E-3 |  |  |  |  |  |  |  |  |  |  |  |  |  |  |  |  |  |  |
| L4 | POWER | 1 oz | 1.3 |  |  |  |  |  | P4 | reference layer |  |  |  | P4 | reference layer |  |  |  |  |  | reference layer |  |  |  |  |  |
|  | Core |  | 4 |  |  | 3.8 | 0 | 8.9999999999999993E-3 |  |  |  |  |  |  |  |  |  |  |  |  |  |  |  |  |  |  |
| L5 | POWER | 1 oz | 1.3 | 0 | 0 |  |  |  | P5 | reference layer |  |  |  | P5 | reference layer |  |  |  |  |  | reference layer |  |  |  |  |  |
|  | Prepreg |  | 16 | 0 | 0 | 4.2 | 0 | 8.9999999999999993E-3 |  |  |  |  |  |  |  |  |  |  |  |  |  |  |  |  |  |  |
| L6 | Signal | 1 oz | 1.3 | 0 | 0 |  |  |  | S6 | 5(L5/L7) | 49.19 |  |  | S6 | 5.5(L5/L7) | 7.5 | 84.85 |  |  |  | 4(L5/L7) | 8 | 97.55 |  |  |  |
|  | Core |  | 4 | 0 | 0 | 3.9 | 0 | 8.9999999999999993E-3 |  |  |  |  |  |  |  |  |  |  |  |  |  |  |  |  |  |  |
| L7 | GND | 1 oz | 1.3 | 0 | 0 |  |  |  | P7 | reference layer |  |  |  | P7 | reference layer |  |  |  |  |  | reference layer |  |  |  |  |  |
|  | Prepreg |  | 3 | 0 | 0 | 3.9 | 0 | 8.9999999999999993E-3 |  |  |  |  |  |  |  |  |  |  |  |  |  |  |  |  |  |  |
| Bottom | Signal | 0.5 oz+plating | 2.1 | 0 | 0 |  |  |  | S8 | 4.75(L7) | 50.46 |  |  | S8 | 5.38(L7) | 6.62 | 85.36 |  |  |  | 4.13(L7) | 9.3699999999999992 | 101.06 |  |  |  |
|  | Mask |  | 0.5 | 0 |  | 3.4 | 0 | 2.5000000000000001E-2 |  |  |  |  |  |  |  |  |  |  |  |  |  |  |  |  |  |  |
| Thickness requirement: 1.6 ± 10% mm |  | mil | 62.999999999999993 |  |  |  |  |  |  |  |  |  |  |  |  |  |  |  |  |  |  |  |  |  |  |  |
|  |  | mm | 1.6002032004064006 |  |  |  |  |  |  |  |  |  |  |  |  |  |  |  |  |  |  |  |  |  |  |  |
| Note: | 1. Unit is mil |  |  |  |  |  |  |  |  |  |  |  |  |  |  |  |  |  |  |  |  |  |  |  |  |  |
|  | 2. The total thickness includes trace and solder mask |  |  |  |  |  |  |  |  |  |  |  |  |  |  |  |  |  |  |  |  |  |  |  |  |  |
|  | 3. Min hole copper thickness is 1.0 mil |  |  |  |  |  |  |  |  |  |  |  |  |  |  |  |  |  |  |  |  |  |  |  |  |  |
|  | 4. Min surface copper thickness 1.5 mil |  |  |  |  |  |  |  |  |  |  |  |  |  |  |  |  |  |  |  |  |  |  |  |  |  |
|  | 5. Impedance Cpk requirement: >=1.33 (Report should be provided) |  |  |  |  |  |  |  |  |  |  |  |  |  |  |  |  |  |  |  |  |  |  |  |  |  |
|  | 6. PCB supplier should design Delta-L coupon and provide measurement results meeting following criteria: |  |  |  |  |  |  |  |  |  |  |  |  |  |  |  |  |  |  |  |  |  |  |  |  |  |
|  | 。  -0.65dB/inch at 4GHz for stripline routing |  |  |  |  |  |  |  |  |  |  |  |  |  |  |  |  |  |  |  |  |  |  |  |  |  |
|  | 。  -0.69dB/inch at 4GHz for microstrip routing |  |  |  |  |  |  |  |  |  |  |  |  |  |  |  |  |  |  |  |  |  |  |  |  |  |
